(kicad_pcb
	(version 20241229)
	(generator "pcbnew")
	(generator_version "9.0")
	(general
		(thickness 1.711)
		(legacy_teardrops no)
	)
	(paper "A4")
	(title_block
		(title "Antmicro Baseboard for Jetson AGX Thor")
		(date "2026-02-18")
		(rev "1.1.0")
		(company "Antmicro Ltd")
		(comment 1 "www.antmicro.com")
		(comment 9 "footprints 146-149 of 1170")
	)
	(layers
		(0 "F.Cu" signal)
		(4 "In1.Cu" signal)
		(6 "In2.Cu" signal)
		(8 "In3.Cu" signal)
		(10 "In4.Cu" jumper)
		(12 "In5.Cu" signal)
		(14 "In6.Cu" signal)
		(16 "In7.Cu" signal)
		(18 "In8.Cu" signal)
		(2 "B.Cu" signal)
		(9 "F.Adhes" user "F.Adhesive")
		(11 "B.Adhes" user "B.Adhesive")
		(13 "F.Paste" user)
		(15 "B.Paste" user)
		(5 "F.SilkS" user "F.Silkscreen")
		(7 "B.SilkS" user "B.Silkscreen")
		(1 "F.Mask" user)
		(3 "B.Mask" user)
		(17 "Dwgs.User" user "User.Drawings")
		(19 "Cmts.User" user "User.Comments")
		(21 "Eco1.User" user "User.Eco1")
		(23 "Eco2.User" user "User.Eco2")
		(25 "Edge.Cuts" user)
		(27 "Margin" user)
		(31 "F.CrtYd" user "F.Courtyard")
		(29 "B.CrtYd" user "B.Courtyard")
		(35 "F.Fab" user)
		(33 "B.Fab" user)
	)
	(footprint "antmicro-footprints:C_0402_1005Metric"
		(layer "F.Cu")
		(at 139.5 59.5)
		(descr "Capacitor SMD 0402")
		(tags "capacitor SMD 0402")
		(property "Reference" "C75"
			(at -1.13 1.37 0)
			(layer "F.SilkS")
			(effects
				(font
					(size 0.7 0.7)
					(thickness 0.15)
				)
				(justify left bottom)
			)
		)
		(property "Value" "C_10u_0402"
			(at -1.022927 2.155213 0)
			(layer "F.Fab")
			(effects
				(font
					(size 0.7 0.7)
					(thickness 0.15)
				)
				(justify left bottom)
			)
		)
		(property "Datasheet" "https://www.yageo.com/en/Chart/Download/pdf/CC0402MRX5R5BB106"
			(at 0 0 0)
			(layer "F.Fab")
			(hide yes)
			(effects
				(font
					(size 1.27 1.27)
					(thickness 0.15)
				)
			)
		)
		(property "Description" "SMD Multilayer Ceramic Capacitor, 10 µF, 6.3 V, 0402 [1005 Metric], ± 20%, X5R, CC Series"
			(at 0 0 0)
			(layer "F.Fab")
			(hide yes)
			(effects
				(font
					(size 1.27 1.27)
					(thickness 0.15)
				)
			)
		)
		(property "MPN" "CC0402MRX5R5BB106"
			(at 0 0 0)
			(unlocked yes)
			(layer "F.Fab")
			(hide yes)
			(effects
				(font
					(size 1 1)
					(thickness 0.15)
				)
			)
		)
		(property "Manufacturer" "YAGEO"
			(at 0 0 0)
			(unlocked yes)
			(layer "F.Fab")
			(hide yes)
			(effects
				(font
					(size 1 1)
					(thickness 0.15)
				)
			)
		)
		(property "License" "Apache-2.0"
			(at 0 0 0)
			(unlocked yes)
			(layer "F.Fab")
			(hide yes)
			(effects
				(font
					(size 1 1)
					(thickness 0.15)
				)
			)
		)
		(property "Author" "Antmicro"
			(at 0 0 0)
			(unlocked yes)
			(layer "F.Fab")
			(hide yes)
			(effects
				(font
					(size 1 1)
					(thickness 0.15)
				)
			)
		)
		(property "Val" "10u"
			(at 0 0 0)
			(unlocked yes)
			(layer "F.Fab")
			(hide yes)
			(effects
				(font
					(size 1 1)
					(thickness 0.15)
				)
			)
		)
		(property "Voltage" ""
			(at 0 0 0)
			(unlocked yes)
			(layer "F.Fab")
			(hide yes)
			(effects
				(font
					(size 1 1)
					(thickness 0.15)
				)
			)
		)
		(property "Dielectric" ""
			(at 0 0 0)
			(unlocked yes)
			(layer "F.Fab")
			(hide yes)
			(effects
				(font
					(size 1 1)
					(thickness 0.15)
				)
			)
		)
		(sheetname "/Power/")
		(sheetfile "power.kicad_sch")
		(attr smd)
		(fp_poly
			(pts
				(xy -0.925 -0.47) (xy -0.925 0.47) (xy 0.925 0.47) (xy 0.925 -0.47)
			)
			(stroke
				(width 0.05)
				(type default)
			)
			(fill no)
			(layer "F.CrtYd")
		)
		(fp_line
			(start -0.494 -0.25)
			(end 0.504 -0.25)
			(stroke
				(width 0.15)
				(type solid)
			)
			(layer "F.Fab")
		)
		(fp_line
			(start -0.494 0.248)
			(end -0.494 -0.25)
			(stroke
				(width 0.15)
				(type solid)
			)
			(layer "F.Fab")
		)
		(fp_line
			(start 0.504 -0.25)
			(end 0.504 0.248)
			(stroke
				(width 0.15)
				(type solid)
			)
			(layer "F.Fab")
		)
		(fp_line
			(start 0.504 0.248)
			(end -0.494 0.248)
			(stroke
				(width 0.15)
				(type solid)
			)
			(layer "F.Fab")
		)
		(fp_text user "Author: Antmicro"
			(at -0.939 3.399 0)
			(layer "F.Fab")
			(effects
				(font
					(size 0.7 0.7)
					(thickness 0.15)
				)
				(justify left bottom)
			)
		)
		(fp_text user "${REFERENCE}"
			(at -0.939 4.599 0)
			(layer "F.Fab")
			(effects
				(font
					(size 0.7 0.7)
					(thickness 0.15)
				)
				(justify left bottom)
			)
		)
		(fp_text user "License: Apache-2.0"
			(at -0.939 5.799 0)
			(layer "F.Fab")
			(effects
				(font
					(size 0.7 0.7)
					(thickness 0.15)
				)
				(justify left bottom)
			)
		)
		(pad "1" smd roundrect
			(at -0.48 0)
			(size 0.59 0.64)
			(layers "F.Cu" "F.Mask" "F.Paste")
			(roundrect_rratio 0.25)
			(net 1 "GND")
			(pintype "passive")
		)
		(pad "2" smd roundrect
			(at 0.48 0)
			(size 0.59 0.64)
			(layers "F.Cu" "F.Mask" "F.Paste")
			(roundrect_rratio 0.25)
			(net 31 "/Power/3V3_LDO")
			(pintype "passive")
		)
	)
	(footprint "antmicro-footprints:R_0402_1005Metric"
		(layer "F.Cu")
		(at 188.476 124.92 -90)
		(descr "Resistor SMD 0402")
		(tags "resistor SMD 0402")
		(property "Reference" "R16"
			(at -1.02 1.376 90)
			(layer "F.SilkS")
			(effects
				(font
					(size 0.7 0.7)
					(thickness 0.15)
				)
				(justify right top)
			)
		)
		(property "Value" "R_12k_0402"
			(at -1.011843 1.772047 90)
			(layer "F.Fab")
			(effects
				(font
					(size 0.7 0.7)
					(thickness 0.15)
				)
				(justify right top)
			)
		)
		(property "Datasheet" "https://www.bourns.com/docs/product-datasheets/cr.pdf"
			(at 0 0 90)
			(layer "F.Fab")
			(hide yes)
			(effects
				(font
					(size 1.27 1.27)
					(thickness 0.15)
				)
			)
		)
		(property "Description" "SMD Chip Resistor, 12 kohm, ± 1%, 62.5 mW, 0402 [1005 Metric], Thick Film, General Purpose"
			(at 0 0 90)
			(layer "F.Fab")
			(hide yes)
			(effects
				(font
					(size 1.27 1.27)
					(thickness 0.15)
				)
			)
		)
		(property "MPN" "CR0402-FX-1202GLF"
			(at 0 0 270)
			(unlocked yes)
			(layer "F.Fab")
			(hide yes)
			(effects
				(font
					(size 1 1)
					(thickness 0.15)
				)
			)
		)
		(property "Manufacturer" "Bourns"
			(at 0 0 270)
			(unlocked yes)
			(layer "F.Fab")
			(hide yes)
			(effects
				(font
					(size 1 1)
					(thickness 0.15)
				)
			)
		)
		(property "License" "Apache-2.0"
			(at 0 0 270)
			(unlocked yes)
			(layer "F.Fab")
			(hide yes)
			(effects
				(font
					(size 1 1)
					(thickness 0.15)
				)
			)
		)
		(property "Author" "Antmicro"
			(at 0 0 270)
			(unlocked yes)
			(layer "F.Fab")
			(hide yes)
			(effects
				(font
					(size 1 1)
					(thickness 0.15)
				)
			)
		)
		(property "Val" "12k"
			(at 0 0 270)
			(unlocked yes)
			(layer "F.Fab")
			(hide yes)
			(effects
				(font
					(size 1 1)
					(thickness 0.15)
				)
			)
		)
		(property "Tolerance" "1%"
			(at 0 0 270)
			(unlocked yes)
			(layer "F.Fab")
			(hide yes)
			(effects
				(font
					(size 1 1)
					(thickness 0.15)
				)
			)
		)
		(property "Current" "1A"
			(at 0 0 270)
			(unlocked yes)
			(layer "F.Fab")
			(hide yes)
			(effects
				(font
					(size 1 1)
					(thickness 0.15)
				)
			)
		)
		(component_classes
			(class "DCDC_1V15")
		)
		(sheetname "/DCDC/")
		(sheetfile "dcdc.kicad_sch")
		(attr smd)
		(fp_rect
			(start -0.925 -0.47)
			(end 0.925 0.47)
			(stroke
				(width 0.05)
				(type default)
			)
			(fill no)
			(layer "F.CrtYd")
		)
		(fp_rect
			(start -0.5 -0.25)
			(end 0.5 0.25)
			(stroke
				(width 0.15)
				(type solid)
			)
			(fill no)
			(layer "F.Fab")
		)
		(fp_text user "${REFERENCE}"
			(at -0.95 3.168 90)
			(layer "F.Fab")
			(effects
				(font
					(size 0.7 0.7)
					(thickness 0.15)
				)
				(justify right top)
			)
		)
		(fp_text user "License: Apache-2.0"
			(at -0.95 5.169 90)
			(layer "F.Fab")
			(effects
				(font
					(size 0.7 0.7)
					(thickness 0.15)
				)
				(justify right top)
			)
		)
		(fp_text user "Author: Antmicro"
			(at -0.95 4.169 90)
			(layer "F.Fab")
			(effects
				(font
					(size 0.7 0.7)
					(thickness 0.15)
				)
				(justify right top)
			)
		)
		(pad "1" smd roundrect
			(at -0.48 0 270)
			(size 0.59 0.64)
			(layers "F.Cu" "F.Mask" "F.Paste")
			(roundrect_rratio 0.25)
			(net 1 "GND")
			(pintype "passive")
		)
		(pad "2" smd roundrect
			(at 0.48 0 270)
			(size 0.59 0.64)
			(layers "F.Cu" "F.Mask" "F.Paste")
			(roundrect_rratio 0.25)
			(net 1232 "/DCDC/1V15_FB")
			(pintype "passive")
		)
	)
	(footprint "antmicro-footprints:C_0402_1005Metric"
		(layer "F.Cu")
		(at 184.05 112.05 -90)
		(descr "Capacitor SMD 0402")
		(tags "capacitor SMD 0402")
		(property "Reference" "C55"
			(at -1.45 -0.55 90)
			(layer "F.SilkS")
			(effects
				(font
					(size 0.7 0.7)
					(thickness 0.15)
				)
				(justify right top)
			)
		)
		(property "Value" "C_4u7_25V_0402"
			(at -1.022927 2.155213 90)
			(layer "F.Fab")
			(effects
				(font
					(size 0.7 0.7)
					(thickness 0.15)
				)
				(justify right top)
			)
		)
		(property "Datasheet" "https://www.murata.com/products/productdetail?partno=GRM155C61E475ME15%23"
			(at 0 0 90)
			(layer "F.Fab")
			(hide yes)
			(effects
				(font
					(size 1.27 1.27)
					(thickness 0.15)
				)
			)
		)
		(property "Description" "SMD Multilayer Ceramic Capacitor"
			(at 0 0 90)
			(layer "F.Fab")
			(hide yes)
			(effects
				(font
					(size 1.27 1.27)
					(thickness 0.15)
				)
			)
		)
		(property "MPN" "GRM155C61E475ME15J"
			(at 0 0 270)
			(unlocked yes)
			(layer "F.Fab")
			(hide yes)
			(effects
				(font
					(size 1 1)
					(thickness 0.15)
				)
			)
		)
		(property "Manufacturer" "Murata"
			(at 0 0 270)
			(unlocked yes)
			(layer "F.Fab")
			(hide yes)
			(effects
				(font
					(size 1 1)
					(thickness 0.15)
				)
			)
		)
		(property "License" "Apache-2.0"
			(at 0 0 270)
			(unlocked yes)
			(layer "F.Fab")
			(hide yes)
			(effects
				(font
					(size 1 1)
					(thickness 0.15)
				)
			)
		)
		(property "Author" "Antmicro"
			(at 0 0 270)
			(unlocked yes)
			(layer "F.Fab")
			(hide yes)
			(effects
				(font
					(size 1 1)
					(thickness 0.15)
				)
			)
		)
		(property "Val" "4u7"
			(at 0 0 270)
			(unlocked yes)
			(layer "F.Fab")
			(hide yes)
			(effects
				(font
					(size 1 1)
					(thickness 0.15)
				)
			)
		)
		(property "Voltage" "25V"
			(at 0 0 270)
			(unlocked yes)
			(layer "F.Fab")
			(hide yes)
			(effects
				(font
					(size 1 1)
					(thickness 0.15)
				)
			)
		)
		(property "Dielectric" "X5S"
			(at 0 0 270)
			(unlocked yes)
			(layer "F.Fab")
			(hide yes)
			(effects
				(font
					(size 1 1)
					(thickness 0.15)
				)
			)
		)
		(sheetname "/DCDC/")
		(sheetfile "dcdc.kicad_sch")
		(attr smd)
		(fp_rect
			(start -0.925 -0.47)
			(end 0.925 0.47)
			(stroke
				(width 0.05)
				(type default)
			)
			(fill no)
			(layer "F.CrtYd")
		)
		(fp_line
			(start -0.494 0.248)
			(end -0.494 -0.25)
			(stroke
				(width 0.15)
				(type solid)
			)
			(layer "F.Fab")
		)
		(fp_line
			(start 0.504 0.248)
			(end -0.494 0.248)
			(stroke
				(width 0.15)
				(type solid)
			)
			(layer "F.Fab")
		)
		(fp_line
			(start -0.494 -0.25)
			(end 0.504 -0.25)
			(stroke
				(width 0.15)
				(type solid)
			)
			(layer "F.Fab")
		)
		(fp_line
			(start 0.504 -0.25)
			(end 0.504 0.248)
			(stroke
				(width 0.15)
				(type solid)
			)
			(layer "F.Fab")
		)
		(fp_text user "Author: Antmicro"
			(at -0.939 3.399 90)
			(layer "F.Fab")
			(effects
				(font
					(size 0.7 0.7)
					(thickness 0.15)
				)
				(justify right top)
			)
		)
		(fp_text user "${REFERENCE}"
			(at -0.939 4.599 90)
			(layer "F.Fab")
			(effects
				(font
					(size 0.7 0.7)
					(thickness 0.15)
				)
				(justify right top)
			)
		)
		(fp_text user "License: Apache-2.0"
			(at -0.939 5.799 90)
			(layer "F.Fab")
			(effects
				(font
					(size 0.7 0.7)
					(thickness 0.15)
				)
				(justify right top)
			)
		)
		(pad "1" smd roundrect
			(at -0.48 0 270)
			(size 0.59 0.64)
			(layers "F.Cu" "F.Mask" "F.Paste")
			(roundrect_rratio 0.25)
			(net 1 "GND")
			(pintype "passive")
		)
		(pad "2" smd roundrect
			(at 0.48 0 270)
			(size 0.59 0.64)
			(layers "F.Cu" "F.Mask" "F.Paste")
			(roundrect_rratio 0.25)
			(net 23 "/DCDC/5V_VDRV")
			(pintype "passive")
		)
	)
	(footprint "antmicro-footprints:C_0402_1005Metric"
		(layer "F.Cu")
		(at 205.6 83.6)
		(descr "Capacitor SMD 0402")
		(tags "capacitor SMD 0402")
		(property "Reference" "C138"
			(at 3.6 -0.4 180)
			(layer "F.SilkS")
			(effects
				(font
					(size 0.7 0.7)
					(thickness 0.15)
				)
				(justify right top)
			)
		)
		(property "Value" "C_4u7_25V_0402"
			(at -1.022927 2.155213 180)
			(layer "F.Fab")
			(effects
				(font
					(size 0.7 0.7)
					(thickness 0.15)
				)
				(justify right top)
			)
		)
		(property "Datasheet" "https://www.murata.com/products/productdetail?partno=GRM155C61E475ME15%23"
			(at 0 0 180)
			(layer "F.Fab")
			(hide yes)
			(effects
				(font
					(size 1.27 1.27)
					(thickness 0.15)
				)
			)
		)
		(property "Description" "SMD Multilayer Ceramic Capacitor"
			(at 0 0 180)
			(layer "F.Fab")
			(hide yes)
			(effects
				(font
					(size 1.27 1.27)
					(thickness 0.15)
				)
			)
		)
		(property "Manufacturer" "Murata"
			(at 0 0 0)
			(unlocked yes)
			(layer "F.Fab")
			(hide yes)
			(effects
				(font
					(size 1 1)
					(thickness 0.15)
				)
			)
		)
		(property "MPN" "GRM155C61E475ME15J"
			(at 0 0 0)
			(unlocked yes)
			(layer "F.Fab")
			(hide yes)
			(effects
				(font
					(size 1 1)
					(thickness 0.15)
				)
			)
		)
		(property "Val" "4u7"
			(at 0 0 0)
			(unlocked yes)
			(layer "F.Fab")
			(hide yes)
			(effects
				(font
					(size 1 1)
					(thickness 0.15)
				)
			)
		)
		(property "License" "Apache-2.0"
			(at 0 0 0)
			(unlocked yes)
			(layer "F.Fab")
			(hide yes)
			(effects
				(font
					(size 1 1)
					(thickness 0.15)
				)
			)
		)
		(property "Author" "Antmicro"
			(at 0 0 0)
			(unlocked yes)
			(layer "F.Fab")
			(hide yes)
			(effects
				(font
					(size 1 1)
					(thickness 0.15)
				)
			)
		)
		(property "Voltage" "25V"
			(at 0 0 0)
			(unlocked yes)
			(layer "F.Fab")
			(hide yes)
			(effects
				(font
					(size 1 1)
					(thickness 0.15)
				)
			)
		)
		(property "Dielectric" "X5S"
			(at 0 0 0)
			(unlocked yes)
			(layer "F.Fab")
			(hide yes)
			(effects
				(font
					(size 1 1)
					(thickness 0.15)
				)
			)
		)
		(sheetname "/USB DP Alt mode/")
		(sheetfile "usb_dp.kicad_sch")
		(attr smd)
		(fp_poly
			(pts
				(xy -0.925 -0.47) (xy -0.925 0.47) (xy 0.925 0.47) (xy 0.925 -0.47)
			)
			(stroke
				(width 0.05)
				(type default)
			)
			(fill no)
			(layer "F.CrtYd")
		)
		(fp_line
			(start -0.494 -0.25)
			(end 0.504 -0.25)
			(stroke
				(width 0.15)
				(type solid)
			)
			(layer "F.Fab")
		)
		(fp_line
			(start -0.494 0.248)
			(end -0.494 -0.25)
			(stroke
				(width 0.15)
				(type solid)
			)
			(layer "F.Fab")
		)
		(fp_line
			(start 0.504 -0.25)
			(end 0.504 0.248)
			(stroke
				(width 0.15)
				(type solid)
			)
			(layer "F.Fab")
		)
		(fp_line
			(start 0.504 0.248)
			(end -0.494 0.248)
			(stroke
				(width 0.15)
				(type solid)
			)
			(layer "F.Fab")
		)
		(fp_text user "License: Apache-2.0"
			(at -0.939 5.799 180)
			(layer "F.Fab")
			(effects
				(font
					(size 0.7 0.7)
					(thickness 0.15)
				)
				(justify right top)
			)
		)
		(fp_text user "Author: Antmicro"
			(at -0.939 3.399 180)
			(layer "F.Fab")
			(effects
				(font
					(size 0.7 0.7)
					(thickness 0.15)
				)
				(justify right top)
			)
		)
		(fp_text user "${REFERENCE}"
			(at -0.939 4.599 180)
			(layer "F.Fab")
			(effects
				(font
					(size 0.7 0.7)
					(thickness 0.15)
				)
				(justify right top)
			)
		)
		(pad "1" smd roundrect
			(at -0.48 0)
			(size 0.59 0.64)
			(layers "F.Cu" "F.Mask" "F.Paste")
			(roundrect_rratio 0.25)
			(net 522 "/Power/USBPD1_HV")
			(pintype "passive")
		)
		(pad "2" smd roundrect
			(at 0.48 0)
			(size 0.59 0.64)
			(layers "F.Cu" "F.Mask" "F.Paste")
			(roundrect_rratio 0.25)
			(net 1 "GND")
			(pintype "passive")
		)
	)
)
